(kicad_pcb
	(version 20260206)
	(generator "pcbnew")
	(generator_version "10.0")
	(general
		(thickness 1.6)
		(legacy_teardrops no)
	)
	(paper "A4")
	(title_block
		(title "peb — Lightning_PEB_BRD.brd")
		(comment 1 "Lightning (Wiwynn / Facebook NVMe JBOF) / footprints 293-300 of 2563")
	)
	(layers
		(0 "F.Cu" signal "TOP")
		(4 "In1.Cu" signal "L2GND")
		(6 "In2.Cu" signal "L3")
		(8 "In3.Cu" signal "L4VCC")
		(10 "In4.Cu" signal "L5VCC")
		(12 "In5.Cu" signal "L6")
		(14 "In6.Cu" signal "L7GND")
		(2 "B.Cu" signal "BOTTOM")
		(9 "F.Adhes" user "F.Adhesive")
		(11 "B.Adhes" user "B.Adhesive")
		(13 "F.Paste" user "Package Geometry/Pastemask Top")
		(15 "B.Paste" user "Package Geometry/Pastemask Bottom")
		(5 "F.SilkS" user "Ref Des/Silkscreen Top")
		(7 "B.SilkS" user "Ref Des/Silkscreen Bottom")
		(1 "F.Mask" user "Board Geometry/Soldermask Top")
		(3 "B.Mask" user "Board Geometry/Soldermask Bottom")
		(17 "Dwgs.User" user "User.Drawings")
		(19 "Cmts.User" user "User.Comments")
		(21 "Eco1.User" user "User.Eco1")
		(23 "Eco2.User" user "User.Eco2")
		(25 "Edge.Cuts" user "Board Geometry/Outline")
		(27 "Margin" user)
		(31 "F.CrtYd" user "Package Geometry/Place Bound Top")
		(29 "B.CrtYd" user "Package Geometry/Place Bound Bottom")
		(35 "F.Fab" user "Ref Des/Assembly Top")
		(33 "B.Fab" user "Ref Des/Assembly Bottom")
	)
	(footprint ""
		(layer "F.Cu")
		(at 24.394922 -109.840522 180)
		(property "Reference" "R9046"
			(at 0 0 180)
			(layer "F.SilkS")
			(hide yes)
			(effects
				(font
					(size 1.27 1.27)
				)
			)
		)
		(property "Value" "56R2F"
			(at 0.064008 -3.993896 180)
			(unlocked yes)
			(layer "F.Fab")
			(hide yes)
			(effects
				(font
					(size 1.016 1.016)
					(thickness 0.1524)
				)
			)
		)
		(property "Device Type" "R402H14"
			(at 0.064008 -5.517896 180)
			(unlocked yes)
			(layer "F.Fab")
			(hide yes)
			(effects
				(font
					(size 1.016 1.016)
					(thickness 0.1524)
				)
			)
		)
		(duplicate_pad_numbers_are_jumpers no)
		(fp_line
			(start 0.508 -0.9398)
			(end -0.508 -0.9398)
			(stroke
				(width 0.1524)
				(type default)
			)
			(layer "F.SilkS")
		)
		(fp_line
			(start -0.508 -0.9398)
			(end -0.508 0.9398)
			(stroke
				(width 0.1524)
				(type default)
			)
			(layer "F.SilkS")
		)
		(fp_rect
			(start -0.508 0.9398)
			(end 0.508 -0.9398)
			(stroke
				(width 0)
				(type default)
			)
			(fill no)
			(layer "F.CrtYd")
		)
		(fp_rect
			(start -0.508 0.9398)
			(end 0.508 -0.9398)
			(stroke
				(width 0)
				(type default)
			)
			(fill no)
			(layer "F.Fab")
		)
		(pad "1" smd custom
			(at 0 -0.4445 180)
			(size 0.1397 0.1397)
			(layers "F.Cu" "F.Mask" "F.Paste")
			(net "BMC_REFCLK_P")
			(options
				(clearance outline)
				(anchor circle)
			)
			(primitives
				(gr_poly
					(pts
						(arc
							(start -0.1778 -0.2794)
							(mid -0.249642 -0.249642)
							(end -0.2794 -0.1778)
						)
						(arc
							(start -0.2794 0.1778)
							(mid -0.249642 0.249642)
							(end -0.1778 0.2794)
						)
						(arc
							(start 0.1778 0.2794)
							(mid 0.249642 0.249642)
							(end 0.2794 0.1778)
						)
						(arc
							(start 0.2794 -0.1778)
							(mid 0.249642 -0.249642)
							(end 0.1778 -0.2794)
						)
					)
					(width 0)
					(fill yes)
				)
			)
		)
		(pad "2" smd custom
			(at 0 0.4445 180)
			(size 0.1397 0.1397)
			(layers "F.Cu" "F.Mask" "F.Paste")
			(net "GND")
			(options
				(clearance outline)
				(anchor circle)
			)
			(primitives
				(gr_poly
					(pts
						(arc
							(start -0.1778 -0.2794)
							(mid -0.249642 -0.249642)
							(end -0.2794 -0.1778)
						)
						(arc
							(start -0.2794 0.1778)
							(mid -0.249642 0.249642)
							(end -0.1778 0.2794)
						)
						(arc
							(start 0.1778 0.2794)
							(mid 0.249642 0.249642)
							(end 0.2794 0.1778)
						)
						(arc
							(start 0.2794 -0.1778)
							(mid 0.249642 -0.249642)
							(end 0.1778 -0.2794)
						)
					)
					(width 0)
					(fill yes)
				)
			)
		)
	)
	(footprint ""
		(layer "F.Cu")
		(at 8.89 -194.3354 180)
		(property "Reference" "R2172"
			(at 0 0 180)
			(layer "F.SilkS")
			(hide yes)
			(effects
				(font
					(size 1.27 1.27)
				)
			)
		)
		(property "Value" "0R2J-2-GP"
			(at 0.064008 -3.993896 180)
			(unlocked yes)
			(layer "F.Fab")
			(hide yes)
			(effects
				(font
					(size 1.016 1.016)
					(thickness 0.1524)
				)
			)
		)
		(property "Device Type" "R402H16"
			(at 0.064008 -5.517896 180)
			(unlocked yes)
			(layer "F.Fab")
			(hide yes)
			(effects
				(font
					(size 1.016 1.016)
					(thickness 0.1524)
				)
			)
		)
		(duplicate_pad_numbers_are_jumpers no)
		(fp_line
			(start 0.508 -0.9398)
			(end -0.508 -0.9398)
			(stroke
				(width 0.1524)
				(type default)
			)
			(layer "F.SilkS")
		)
		(fp_line
			(start -0.508 -0.9398)
			(end -0.508 0.9398)
			(stroke
				(width 0.1524)
				(type default)
			)
			(layer "F.SilkS")
		)
		(fp_rect
			(start -0.508 0.9398)
			(end 0.508 -0.9398)
			(stroke
				(width 0)
				(type default)
			)
			(fill no)
			(layer "F.CrtYd")
		)
		(fp_rect
			(start -0.508 0.9398)
			(end 0.508 -0.9398)
			(stroke
				(width 0)
				(type default)
			)
			(fill no)
			(layer "F.Fab")
		)
		(pad "1" smd custom
			(at 0 -0.4445 180)
			(size 0.1397 0.1397)
			(layers "F.Cu" "F.Mask" "F.Paste")
			(net "MB0_CM_ADR2_R")
			(options
				(clearance outline)
				(anchor circle)
			)
			(primitives
				(gr_poly
					(pts
						(arc
							(start -0.1778 -0.2794)
							(mid -0.249642 -0.249642)
							(end -0.2794 -0.1778)
						)
						(arc
							(start -0.2794 0.1778)
							(mid -0.249642 0.249642)
							(end -0.1778 0.2794)
						)
						(arc
							(start 0.1778 0.2794)
							(mid 0.249642 0.249642)
							(end 0.2794 0.1778)
						)
						(arc
							(start 0.2794 -0.1778)
							(mid 0.249642 -0.249642)
							(end 0.1778 -0.2794)
						)
					)
					(width 0)
					(fill yes)
				)
			)
		)
		(pad "2" smd custom
			(at 0 0.4445 180)
			(size 0.1397 0.1397)
			(layers "F.Cu" "F.Mask" "F.Paste")
			(net "AGND_CURRENT_MON")
			(options
				(clearance outline)
				(anchor circle)
			)
			(primitives
				(gr_poly
					(pts
						(arc
							(start -0.1778 -0.2794)
							(mid -0.249642 -0.249642)
							(end -0.2794 -0.1778)
						)
						(arc
							(start -0.2794 0.1778)
							(mid -0.249642 0.249642)
							(end -0.1778 0.2794)
						)
						(arc
							(start 0.1778 0.2794)
							(mid 0.249642 0.249642)
							(end 0.2794 0.1778)
						)
						(arc
							(start 0.2794 -0.1778)
							(mid 0.249642 -0.249642)
							(end 0.1778 -0.2794)
						)
					)
					(width 0)
					(fill yes)
				)
			)
		)
	)
	(footprint ""
		(layer "F.Cu")
		(at 306.819046 -33.51022)
		(property "Reference" "C18"
			(at 0 0 0)
			(layer "F.SilkS")
			(hide yes)
			(effects
				(font
					(size 1.27 1.27)
				)
			)
		)
		(property "Value" "SCD22U10V2KX-1GP"
			(at 1.1811 -2.7051 0)
			(unlocked yes)
			(layer "F.Fab")
			(hide yes)
			(effects
				(font
					(size 1.016 1.016)
					(thickness 0.1524)
				)
			)
		)
		(property "Device Type" "C402H22"
			(at 1.1811 -4.2291 0)
			(unlocked yes)
			(layer "F.Fab")
			(hide yes)
			(effects
				(font
					(size 1.016 1.016)
					(thickness 0.1524)
				)
			)
		)
		(duplicate_pad_numbers_are_jumpers no)
		(fp_rect
			(start -0.4318 0.9525)
			(end 0.4318 -0.9525)
			(stroke
				(width 0)
				(type default)
			)
			(fill no)
			(layer "F.CrtYd")
		)
		(fp_rect
			(start -0.4318 0.9525)
			(end 0.4318 -0.9525)
			(stroke
				(width 0)
				(type default)
			)
			(fill no)
			(layer "F.Fab")
		)
		(pad "1" smd custom
			(at 0 -0.4445)
			(size 0.1524 0.1524)
			(layers "F.Cu" "F.Mask" "F.Paste")
			(net "PCIE_TX_CAP_N8")
			(options
				(clearance outline)
				(anchor circle)
			)
			(primitives
				(gr_poly
					(pts
						(arc
							(start 0.3048 -0.2032)
							(mid 0.275042 -0.275042)
							(end 0.2032 -0.3048)
						)
						(arc
							(start -0.2032 -0.3048)
							(mid -0.275042 -0.275042)
							(end -0.3048 -0.2032)
						)
						(arc
							(start -0.3048 0.2032)
							(mid -0.275042 0.275042)
							(end -0.2032 0.3048)
						)
						(arc
							(start 0.2032 0.3048)
							(mid 0.275042 0.275042)
							(end 0.3048 0.2032)
						)
					)
					(width 0)
					(fill yes)
				)
			)
		)
		(pad "2" smd custom
			(at 0 0.4445)
			(size 0.1524 0.1524)
			(layers "F.Cu" "F.Mask" "F.Paste")
			(net "PCIE_TX_N8")
			(options
				(clearance outline)
				(anchor circle)
			)
			(primitives
				(gr_poly
					(pts
						(arc
							(start 0.3048 -0.2032)
							(mid 0.275042 -0.275042)
							(end 0.2032 -0.3048)
						)
						(arc
							(start -0.2032 -0.3048)
							(mid -0.275042 -0.275042)
							(end -0.3048 -0.2032)
						)
						(arc
							(start -0.3048 0.2032)
							(mid -0.275042 0.275042)
							(end -0.2032 0.3048)
						)
						(arc
							(start 0.2032 0.3048)
							(mid 0.275042 0.275042)
							(end 0.3048 0.2032)
						)
					)
					(width 0)
					(fill yes)
				)
			)
		)
	)
	(footprint ""
		(layer "F.Cu")
		(at 41.275 -56.388)
		(property "Reference" "TP147"
			(at 0 0 0)
			(layer "F.SilkS")
			(hide yes)
			(effects
				(font
					(size 1.27 1.27)
				)
			)
		)
		(property "Value" "TPAD28-2-GP"
			(at -0.0127 -1.6637 0)
			(unlocked yes)
			(layer "F.Fab")
			(hide yes)
			(effects
				(font
					(size 1.016 1.016)
					(thickness 0.1524)
				)
			)
		)
		(property "Device Type" "TPAD28"
			(at -0.0127 -3.1877 0)
			(unlocked yes)
			(layer "F.Fab")
			(hide yes)
			(effects
				(font
					(size 1.016 1.016)
					(thickness 0.1524)
				)
			)
		)
		(duplicate_pad_numbers_are_jumpers no)
		(fp_poly
			(pts
				(arc
					(start 0.3556 0)
					(mid -0.3556 0)
					(end 0.3556 0)
				)
			)
			(stroke
				(width 0)
				(type default)
			)
			(fill no)
			(layer "F.CrtYd")
		)
		(fp_poly
			(pts
				(arc
					(start 0.6096 0)
					(mid -0.6096 0)
					(end 0.6096 0)
				)
			)
			(stroke
				(width 0)
				(type default)
			)
			(fill no)
			(layer "F.Fab")
		)
		(pad "1" smd circle
			(at 0 0)
			(size 0.7112 0.7112)
			(layers "F.Cu" "F.Mask" "F.Paste")
			(net "USB_OC#")
		)
	)
	(footprint ""
		(layer "F.Cu")
		(at 300.268894 -33.560258)
		(property "Reference" "C14"
			(at 0 0 0)
			(layer "F.SilkS")
			(hide yes)
			(effects
				(font
					(size 1.27 1.27)
				)
			)
		)
		(property "Value" "SCD22U10V2KX-1GP"
			(at 1.1811 -2.7051 0)
			(unlocked yes)
			(layer "F.Fab")
			(hide yes)
			(effects
				(font
					(size 1.016 1.016)
					(thickness 0.1524)
				)
			)
		)
		(property "Device Type" "C402H22"
			(at 1.1811 -4.2291 0)
			(unlocked yes)
			(layer "F.Fab")
			(hide yes)
			(effects
				(font
					(size 1.016 1.016)
					(thickness 0.1524)
				)
			)
		)
		(duplicate_pad_numbers_are_jumpers no)
		(fp_rect
			(start -0.4318 0.9525)
			(end 0.4318 -0.9525)
			(stroke
				(width 0)
				(type default)
			)
			(fill no)
			(layer "F.CrtYd")
		)
		(fp_rect
			(start -0.4318 0.9525)
			(end 0.4318 -0.9525)
			(stroke
				(width 0)
				(type default)
			)
			(fill no)
			(layer "F.Fab")
		)
		(pad "1" smd custom
			(at 0 -0.4445)
			(size 0.1524 0.1524)
			(layers "F.Cu" "F.Mask" "F.Paste")
			(net "PCIE_TX_CAP_N5")
			(options
				(clearance outline)
				(anchor circle)
			)
			(primitives
				(gr_poly
					(pts
						(arc
							(start 0.3048 -0.2032)
							(mid 0.275042 -0.275042)
							(end 0.2032 -0.3048)
						)
						(arc
							(start -0.2032 -0.3048)
							(mid -0.275042 -0.275042)
							(end -0.3048 -0.2032)
						)
						(arc
							(start -0.3048 0.2032)
							(mid -0.275042 0.275042)
							(end -0.2032 0.3048)
						)
						(arc
							(start 0.2032 0.3048)
							(mid 0.275042 0.275042)
							(end 0.3048 0.2032)
						)
					)
					(width 0)
					(fill yes)
				)
			)
		)
		(pad "2" smd custom
			(at 0 0.4445)
			(size 0.1524 0.1524)
			(layers "F.Cu" "F.Mask" "F.Paste")
			(net "PCIE_TX_N5")
			(options
				(clearance outline)
				(anchor circle)
			)
			(primitives
				(gr_poly
					(pts
						(arc
							(start 0.3048 -0.2032)
							(mid 0.275042 -0.275042)
							(end 0.2032 -0.3048)
						)
						(arc
							(start -0.2032 -0.3048)
							(mid -0.275042 -0.275042)
							(end -0.3048 -0.2032)
						)
						(arc
							(start -0.3048 0.2032)
							(mid -0.275042 0.275042)
							(end -0.2032 0.3048)
						)
						(arc
							(start 0.2032 0.3048)
							(mid 0.275042 0.275042)
							(end 0.3048 0.2032)
						)
					)
					(width 0)
					(fill yes)
				)
			)
		)
	)
	(footprint ""
		(layer "F.Cu")
		(at 225.114104 -203.720192 180)
		(property "Reference" "R7977"
			(at 0 0 180)
			(layer "F.SilkS")
			(hide yes)
			(effects
				(font
					(size 1.27 1.27)
				)
			)
		)
		(property "Value" "0R2J-2-GP"
			(at 0.064008 -3.993896 180)
			(unlocked yes)
			(layer "F.Fab")
			(hide yes)
			(effects
				(font
					(size 1.016 1.016)
					(thickness 0.1524)
				)
			)
		)
		(property "Device Type" "R402H16"
			(at 0.064008 -5.517896 180)
			(unlocked yes)
			(layer "F.Fab")
			(hide yes)
			(effects
				(font
					(size 1.016 1.016)
					(thickness 0.1524)
				)
			)
		)
		(duplicate_pad_numbers_are_jumpers no)
		(fp_line
			(start 0.508 -0.9398)
			(end -0.508 -0.9398)
			(stroke
				(width 0.1524)
				(type default)
			)
			(layer "F.SilkS")
		)
		(fp_line
			(start -0.508 -0.9398)
			(end -0.508 0.9398)
			(stroke
				(width 0.1524)
				(type default)
			)
			(layer "F.SilkS")
		)
		(fp_rect
			(start -0.508 0.9398)
			(end 0.508 -0.9398)
			(stroke
				(width 0)
				(type default)
			)
			(fill no)
			(layer "F.CrtYd")
		)
		(fp_rect
			(start -0.508 0.9398)
			(end 0.508 -0.9398)
			(stroke
				(width 0)
				(type default)
			)
			(fill no)
			(layer "F.Fab")
		)
		(pad "1" smd custom
			(at 0 -0.4445 180)
			(size 0.1397 0.1397)
			(layers "F.Cu" "F.Mask" "F.Paste")
			(net "SSD_PERST#12")
			(options
				(clearance outline)
				(anchor circle)
			)
			(primitives
				(gr_poly
					(pts
						(arc
							(start -0.1778 -0.2794)
							(mid -0.249642 -0.249642)
							(end -0.2794 -0.1778)
						)
						(arc
							(start -0.2794 0.1778)
							(mid -0.249642 0.249642)
							(end -0.1778 0.2794)
						)
						(arc
							(start 0.1778 0.2794)
							(mid 0.249642 0.249642)
							(end 0.2794 0.1778)
						)
						(arc
							(start 0.2794 -0.1778)
							(mid 0.249642 -0.249642)
							(end 0.1778 -0.2794)
						)
					)
					(width 0)
					(fill yes)
				)
			)
		)
		(pad "2" smd custom
			(at 0 0.4445 180)
			(size 0.1397 0.1397)
			(layers "F.Cu" "F.Mask" "F.Paste")
			(net "SSD_PERST#12_R")
			(options
				(clearance outline)
				(anchor circle)
			)
			(primitives
				(gr_poly
					(pts
						(arc
							(start -0.1778 -0.2794)
							(mid -0.249642 -0.249642)
							(end -0.2794 -0.1778)
						)
						(arc
							(start -0.2794 0.1778)
							(mid -0.249642 0.249642)
							(end -0.1778 0.2794)
						)
						(arc
							(start 0.1778 0.2794)
							(mid 0.249642 0.249642)
							(end 0.2794 0.1778)
						)
						(arc
							(start 0.2794 -0.1778)
							(mid 0.249642 -0.249642)
							(end 0.1778 -0.2794)
						)
					)
					(width 0)
					(fill yes)
				)
			)
		)
	)
	(footprint ""
		(layer "F.Cu")
		(at 331.216 -21.59)
		(property "Reference" "SR714"
			(at 0 0 0)
			(layer "F.SilkS")
			(hide yes)
			(effects
				(font
					(size 1.27 1.27)
				)
			)
		)
		(property "Value" "150R2F-1-GP"
			(at 0.064008 -3.993896 0)
			(unlocked yes)
			(layer "F.Fab")
			(hide yes)
			(effects
				(font
					(size 1.016 1.016)
					(thickness 0.1524)
				)
			)
		)
		(property "Device Type" "R402H16"
			(at 0.064008 -5.517896 0)
			(unlocked yes)
			(layer "F.Fab")
			(hide yes)
			(effects
				(font
					(size 1.016 1.016)
					(thickness 0.1524)
				)
			)
		)
		(duplicate_pad_numbers_are_jumpers no)
		(fp_line
			(start -0.508 -0.9398)
			(end -0.508 0.9398)
			(stroke
				(width 0.1524)
				(type default)
			)
			(layer "F.SilkS")
		)
		(fp_line
			(start 0.508 -0.9398)
			(end -0.508 -0.9398)
			(stroke
				(width 0.1524)
				(type default)
			)
			(layer "F.SilkS")
		)
		(fp_rect
			(start -0.508 0.9398)
			(end 0.508 -0.9398)
			(stroke
				(width 0)
				(type default)
			)
			(fill no)
			(layer "F.CrtYd")
		)
		(fp_rect
			(start -0.508 0.9398)
			(end 0.508 -0.9398)
			(stroke
				(width 0)
				(type default)
			)
			(fill no)
			(layer "F.Fab")
		)
		(pad "1" smd custom
			(at 0 -0.4445)
			(size 0.1397 0.1397)
			(layers "F.Cu" "F.Mask" "F.Paste")
			(net "P3V3_STBY")
			(options
				(clearance outline)
				(anchor circle)
			)
			(primitives
				(gr_poly
					(pts
						(arc
							(start -0.1778 -0.2794)
							(mid -0.249642 -0.249642)
							(end -0.2794 -0.1778)
						)
						(arc
							(start -0.2794 0.1778)
							(mid -0.249642 0.249642)
							(end -0.1778 0.2794)
						)
						(arc
							(start 0.1778 0.2794)
							(mid 0.249642 0.249642)
							(end 0.2794 0.1778)
						)
						(arc
							(start 0.2794 -0.1778)
							(mid 0.249642 -0.249642)
							(end 0.1778 -0.2794)
						)
					)
					(width 0)
					(fill yes)
				)
			)
		)
		(pad "2" smd custom
			(at 0 0.4445)
			(size 0.1397 0.1397)
			(layers "F.Cu" "F.Mask" "F.Paste")
			(net "LED_R_5")
			(options
				(clearance outline)
				(anchor circle)
			)
			(primitives
				(gr_poly
					(pts
						(arc
							(start -0.1778 -0.2794)
							(mid -0.249642 -0.249642)
							(end -0.2794 -0.1778)
						)
						(arc
							(start -0.2794 0.1778)
							(mid -0.249642 0.249642)
							(end -0.1778 0.2794)
						)
						(arc
							(start 0.1778 0.2794)
							(mid 0.249642 0.249642)
							(end 0.2794 0.1778)
						)
						(arc
							(start 0.2794 -0.1778)
							(mid 0.249642 -0.249642)
							(end 0.1778 -0.2794)
						)
					)
					(width 0)
					(fill yes)
				)
			)
		)
	)
	(footprint ""
		(layer "F.Cu")
		(at 234.6706 -13.1064 180)
		(property "Reference" "C465"
			(at 0 0 180)
			(layer "F.SilkS")
			(hide yes)
			(effects
				(font
					(size 1.27 1.27)
				)
			)
		)
		(property "Value" "SC47U4V5MX-2-GP"
			(at -0.0762 -6.1214 180)
			(unlocked yes)
			(layer "F.Fab")
			(hide yes)
			(effects
				(font
					(size 1.016 1.016)
					(thickness 0.1524)
				)
			)
		)
		(property "Device Type" "C805H58"
			(at -0.0762 -8.1534 180)
			(unlocked yes)
			(layer "F.Fab")
			(hide yes)
			(effects
				(font
					(size 1.016 1.016)
					(thickness 0.1524)
				)
			)
		)
		(duplicate_pad_numbers_are_jumpers no)
		(fp_line
			(start 0.635 0)
			(end -0.635 0)
			(stroke
				(width 0.508)
				(type default)
			)
			(layer "F.SilkS")
		)
		(fp_rect
			(start -0.9652 1.778)
			(end 0.9652 -1.778)
			(stroke
				(width 0)
				(type default)
			)
			(fill no)
			(layer "F.CrtYd")
		)
		(fp_poly
			(pts
				(xy -0.9652 -1.778) (xy 0.9652 -1.778) (xy 0.9652 1.778) (xy -0.9652 1.778)
			)
			(stroke
				(width 0)
				(type default)
			)
			(fill no)
			(layer "F.Fab")
		)
		(pad "1" smd rect
			(at 0 -0.9652 180)
			(size 1.397 1.143)
			(layers "F.Cu" "F.Mask" "F.Paste")
			(net "DUT_VDDO_REF")
		)
		(pad "2" smd rect
			(at 0 0.9652 180)
			(size 1.397 1.143)
			(layers "F.Cu" "F.Mask" "F.Paste")
			(net "GND")
		)
	)
)
